(kicad_pcb
	(version 20260206)
	(generator "pcbnew")
	(generator_version "10.0")
	(general
		(thickness 1.6)
		(legacy_teardrops no)
	)
	(paper "A4")
	(title_block
		(title "01162023_DA0F0TEBIF0_F0T_Expander_BD_F_brd_V02_OCP.brd")
		(comment 1 "Grand Teton / footprints 4028-4034 of 9728")
	)
	(layers
		(0 "F.Cu" signal "TOP")
		(4 "In1.Cu" signal "GND")
		(6 "In2.Cu" signal "VCC")
		(8 "In3.Cu" signal "VCC1")
		(10 "In4.Cu" signal "GND1")
		(12 "In5.Cu" signal "IN1")
		(14 "In6.Cu" signal "GND2")
		(16 "In7.Cu" signal "IN2")
		(18 "In8.Cu" signal "GND3")
		(20 "In9.Cu" signal "IN3")
		(22 "In10.Cu" signal "GND4")
		(24 "In11.Cu" signal "IN4")
		(26 "In12.Cu" signal "GND5")
		(28 "In13.Cu" signal "IN5")
		(30 "In14.Cu" signal "GND6")
		(32 "In15.Cu" signal "IN6")
		(34 "In16.Cu" signal "GND7")
		(2 "B.Cu" signal "BOTTOM")
		(9 "F.Adhes" user "F.Adhesive")
		(11 "B.Adhes" user "B.Adhesive")
		(13 "F.Paste" user "Package Geometry/Pastemask Top")
		(15 "B.Paste" user "Package Geometry/Pastemask Bottom")
		(5 "F.SilkS" user "Ref Des/Silkscreen Top")
		(7 "B.SilkS" user "Ref Des/Silkscreen Bottom")
		(1 "F.Mask" user "Board Geometry/Soldermask Top")
		(3 "B.Mask" user "Board Geometry/Soldermask Bottom")
		(17 "Dwgs.User" user "User.Drawings")
		(19 "Cmts.User" user "User.Comments")
		(21 "Eco1.User" user "User.Eco1")
		(23 "Eco2.User" user "User.Eco2")
		(25 "Edge.Cuts" user "Board Geometry/Outline")
		(27 "Margin" user)
		(31 "F.CrtYd" user "Package Geometry/Place Bound Top")
		(29 "B.CrtYd" user "Package Geometry/Place Bound Bottom")
		(35 "F.Fab" user "Ref Des/Assembly Top")
		(33 "B.Fab" user "Ref Des/Assembly Bottom")
	)
	(footprint ""
		(layer "F.Cu")
		(at 331.175614 -123.795028)
		(property "Reference" "C2880"
			(at 0 0 0)
			(layer "F.SilkS")
			(hide yes)
			(effects
				(font
					(size 1.27 1.27)
				)
			)
		)
		(property "Value" ""
			(at 0 0 0)
			(layer "F.Fab")
			(effects
				(font
					(size 1.27 1.27)
				)
			)
		)
		(duplicate_pad_numbers_are_jumpers no)
		(fp_line
			(start -0.7874 -0.4064)
			(end 0.7874 -0.4064)
			(stroke
				(width 0.1524)
				(type default)
			)
			(layer "F.SilkS")
		)
		(fp_line
			(start -0.7874 0.4064)
			(end -0.7874 -0.4064)
			(stroke
				(width 0.1524)
				(type default)
			)
			(layer "F.SilkS")
		)
		(fp_line
			(start 0.7874 -0.4064)
			(end 0.7874 0.4064)
			(stroke
				(width 0.1524)
				(type default)
			)
			(layer "F.SilkS")
		)
		(fp_line
			(start 0.7874 0.4064)
			(end -0.7874 0.4064)
			(stroke
				(width 0.1524)
				(type default)
			)
			(layer "F.SilkS")
		)
		(fp_line
			(start -0.67945 -0.305054)
			(end -0.12065 -0.305054)
			(stroke
				(width 0.1)
				(type default)
			)
			(layer "F.Fab")
		)
		(fp_line
			(start -0.67945 0.3048)
			(end -0.67945 -0.305054)
			(stroke
				(width 0.1)
				(type default)
			)
			(layer "F.Fab")
		)
		(fp_line
			(start -0.12065 -0.305054)
			(end -0.12065 -0.2794)
			(stroke
				(width 0.1)
				(type default)
			)
			(layer "F.Fab")
		)
		(fp_line
			(start -0.12065 -0.2794)
			(end 0.12065 -0.2794)
			(stroke
				(width 0.1)
				(type default)
			)
			(layer "F.Fab")
		)
		(fp_line
			(start -0.12065 0.2794)
			(end -0.12065 0.3048)
			(stroke
				(width 0.1)
				(type default)
			)
			(layer "F.Fab")
		)
		(fp_line
			(start -0.12065 0.3048)
			(end -0.67945 0.3048)
			(stroke
				(width 0.1)
				(type default)
			)
			(layer "F.Fab")
		)
		(fp_line
			(start 0.120396 0.2794)
			(end -0.12065 0.2794)
			(stroke
				(width 0.1)
				(type default)
			)
			(layer "F.Fab")
		)
		(fp_line
			(start 0.120396 0.3048)
			(end 0.120396 0.2794)
			(stroke
				(width 0.1)
				(type default)
			)
			(layer "F.Fab")
		)
		(fp_line
			(start 0.12065 -0.3048)
			(end 0.67945 -0.3048)
			(stroke
				(width 0.1)
				(type default)
			)
			(layer "F.Fab")
		)
		(fp_line
			(start 0.12065 -0.2794)
			(end 0.12065 -0.3048)
			(stroke
				(width 0.1)
				(type default)
			)
			(layer "F.Fab")
		)
		(fp_line
			(start 0.67945 -0.3048)
			(end 0.67945 0.3048)
			(stroke
				(width 0.1)
				(type default)
			)
			(layer "F.Fab")
		)
		(fp_line
			(start 0.67945 0.3048)
			(end 0.120396 0.3048)
			(stroke
				(width 0.1)
				(type default)
			)
			(layer "F.Fab")
		)
		(pad "1" smd circle
			(at -0.40005 0)
			(size 0 0)
			(layers "F.Cu" "F.Mask" "F.Paste")
			(net "HP_NIC5_EN")
		)
		(pad "2" smd circle
			(at 0.40005 0)
			(size 0 0)
			(layers "F.Cu" "F.Mask" "F.Paste")
			(net "GND")
		)
	)
	(footprint ""
		(layer "F.Cu")
		(at 431.594006 -34.248852)
		(property "Reference" "R5704"
			(at 0 0 0)
			(layer "F.SilkS")
			(hide yes)
			(effects
				(font
					(size 1.27 1.27)
				)
			)
		)
		(property "Value" ""
			(at 0 0 0)
			(layer "F.Fab")
			(effects
				(font
					(size 1.27 1.27)
				)
			)
		)
		(duplicate_pad_numbers_are_jumpers no)
		(fp_line
			(start -0.7874 -0.4064)
			(end 0.7874 -0.4064)
			(stroke
				(width 0.1524)
				(type default)
			)
			(layer "F.SilkS")
		)
		(fp_line
			(start -0.7874 0.4064)
			(end -0.7874 -0.4064)
			(stroke
				(width 0.1524)
				(type default)
			)
			(layer "F.SilkS")
		)
		(fp_line
			(start 0.7874 -0.4064)
			(end 0.7874 0.4064)
			(stroke
				(width 0.1524)
				(type default)
			)
			(layer "F.SilkS")
		)
		(fp_line
			(start 0.7874 0.4064)
			(end -0.7874 0.4064)
			(stroke
				(width 0.1524)
				(type default)
			)
			(layer "F.SilkS")
		)
		(fp_line
			(start -0.67945 -0.305054)
			(end -0.12065 -0.305054)
			(stroke
				(width 0.1)
				(type default)
			)
			(layer "F.Fab")
		)
		(fp_line
			(start -0.67945 0.3048)
			(end -0.67945 -0.305054)
			(stroke
				(width 0.1)
				(type default)
			)
			(layer "F.Fab")
		)
		(fp_line
			(start -0.12065 -0.305054)
			(end -0.12065 -0.2794)
			(stroke
				(width 0.1)
				(type default)
			)
			(layer "F.Fab")
		)
		(fp_line
			(start -0.12065 -0.2794)
			(end 0.12065 -0.2794)
			(stroke
				(width 0.1)
				(type default)
			)
			(layer "F.Fab")
		)
		(fp_line
			(start -0.12065 0.2794)
			(end -0.12065 0.3048)
			(stroke
				(width 0.1)
				(type default)
			)
			(layer "F.Fab")
		)
		(fp_line
			(start -0.12065 0.3048)
			(end -0.67945 0.3048)
			(stroke
				(width 0.1)
				(type default)
			)
			(layer "F.Fab")
		)
		(fp_line
			(start 0.120396 0.2794)
			(end -0.12065 0.2794)
			(stroke
				(width 0.1)
				(type default)
			)
			(layer "F.Fab")
		)
		(fp_line
			(start 0.120396 0.3048)
			(end 0.120396 0.2794)
			(stroke
				(width 0.1)
				(type default)
			)
			(layer "F.Fab")
		)
		(fp_line
			(start 0.12065 -0.3048)
			(end 0.67945 -0.3048)
			(stroke
				(width 0.1)
				(type default)
			)
			(layer "F.Fab")
		)
		(fp_line
			(start 0.12065 -0.2794)
			(end 0.12065 -0.3048)
			(stroke
				(width 0.1)
				(type default)
			)
			(layer "F.Fab")
		)
		(fp_line
			(start 0.67945 -0.3048)
			(end 0.67945 0.3048)
			(stroke
				(width 0.1)
				(type default)
			)
			(layer "F.Fab")
		)
		(fp_line
			(start 0.67945 0.3048)
			(end 0.120396 0.3048)
			(stroke
				(width 0.1)
				(type default)
			)
			(layer "F.Fab")
		)
		(pad "1" smd circle
			(at -0.40005 0)
			(size 0 0)
			(layers "F.Cu" "F.Mask" "F.Paste")
			(net "RST_SMB_SSD15_ISO_N")
		)
		(pad "2" smd circle
			(at 0.40005 0)
			(size 0 0)
			(layers "F.Cu" "F.Mask" "F.Paste")
			(net "P3V3_SSD15")
		)
	)
	(footprint ""
		(layer "F.Cu")
		(at 78.243684 -46.90491)
		(property "Reference" "R530"
			(at 0 0 0)
			(layer "F.SilkS")
			(hide yes)
			(effects
				(font
					(size 1.27 1.27)
				)
			)
		)
		(property "Value" ""
			(at 0 0 0)
			(layer "F.Fab")
			(effects
				(font
					(size 1.27 1.27)
				)
			)
		)
		(duplicate_pad_numbers_are_jumpers no)
		(fp_line
			(start -0.7874 -0.4064)
			(end 0.7874 -0.4064)
			(stroke
				(width 0.1524)
				(type default)
			)
			(layer "F.SilkS")
		)
		(fp_line
			(start -0.7874 0.4064)
			(end -0.7874 -0.4064)
			(stroke
				(width 0.1524)
				(type default)
			)
			(layer "F.SilkS")
		)
		(fp_line
			(start 0.7874 -0.4064)
			(end 0.7874 0.4064)
			(stroke
				(width 0.1524)
				(type default)
			)
			(layer "F.SilkS")
		)
		(fp_line
			(start 0.7874 0.4064)
			(end -0.7874 0.4064)
			(stroke
				(width 0.1524)
				(type default)
			)
			(layer "F.SilkS")
		)
		(fp_line
			(start -0.67945 -0.305054)
			(end -0.12065 -0.305054)
			(stroke
				(width 0.1)
				(type default)
			)
			(layer "F.Fab")
		)
		(fp_line
			(start -0.67945 0.3048)
			(end -0.67945 -0.305054)
			(stroke
				(width 0.1)
				(type default)
			)
			(layer "F.Fab")
		)
		(fp_line
			(start -0.12065 -0.305054)
			(end -0.12065 -0.2794)
			(stroke
				(width 0.1)
				(type default)
			)
			(layer "F.Fab")
		)
		(fp_line
			(start -0.12065 -0.2794)
			(end 0.12065 -0.2794)
			(stroke
				(width 0.1)
				(type default)
			)
			(layer "F.Fab")
		)
		(fp_line
			(start -0.12065 0.2794)
			(end -0.12065 0.3048)
			(stroke
				(width 0.1)
				(type default)
			)
			(layer "F.Fab")
		)
		(fp_line
			(start -0.12065 0.3048)
			(end -0.67945 0.3048)
			(stroke
				(width 0.1)
				(type default)
			)
			(layer "F.Fab")
		)
		(fp_line
			(start 0.120396 0.2794)
			(end -0.12065 0.2794)
			(stroke
				(width 0.1)
				(type default)
			)
			(layer "F.Fab")
		)
		(fp_line
			(start 0.120396 0.3048)
			(end 0.120396 0.2794)
			(stroke
				(width 0.1)
				(type default)
			)
			(layer "F.Fab")
		)
		(fp_line
			(start 0.12065 -0.3048)
			(end 0.67945 -0.3048)
			(stroke
				(width 0.1)
				(type default)
			)
			(layer "F.Fab")
		)
		(fp_line
			(start 0.12065 -0.2794)
			(end 0.12065 -0.3048)
			(stroke
				(width 0.1)
				(type default)
			)
			(layer "F.Fab")
		)
		(fp_line
			(start 0.67945 -0.3048)
			(end 0.67945 0.3048)
			(stroke
				(width 0.1)
				(type default)
			)
			(layer "F.Fab")
		)
		(fp_line
			(start 0.67945 0.3048)
			(end 0.120396 0.3048)
			(stroke
				(width 0.1)
				(type default)
			)
			(layer "F.Fab")
		)
		(pad "1" smd circle
			(at -0.40005 0)
			(size 0 0)
			(layers "F.Cu" "F.Mask" "F.Paste")
			(net "SSD2_ADC_ALERT_N")
		)
		(pad "2" smd circle
			(at 0.40005 0)
			(size 0 0)
			(layers "F.Cu" "F.Mask" "F.Paste")
			(net "SSD_0_7_ADC_ALERT_N")
		)
	)
	(footprint ""
		(layer "F.Cu")
		(at 394.038582 -44.341542 90)
		(property "Reference" "C338"
			(at 0 0 90)
			(layer "F.SilkS")
			(hide yes)
			(effects
				(font
					(size 1.27 1.27)
				)
			)
		)
		(property "Value" ""
			(at 0 0 90)
			(layer "F.Fab")
			(effects
				(font
					(size 1.27 1.27)
				)
			)
		)
		(duplicate_pad_numbers_are_jumpers no)
		(fp_line
			(start 0.7874 -0.4064)
			(end 0.7874 0.4064)
			(stroke
				(width 0.1524)
				(type default)
			)
			(layer "F.SilkS")
		)
		(fp_line
			(start -0.7874 -0.4064)
			(end 0.7874 -0.4064)
			(stroke
				(width 0.1524)
				(type default)
			)
			(layer "F.SilkS")
		)
		(fp_line
			(start 0.7874 0.4064)
			(end -0.7874 0.4064)
			(stroke
				(width 0.1524)
				(type default)
			)
			(layer "F.SilkS")
		)
		(fp_line
			(start -0.7874 0.4064)
			(end -0.7874 -0.4064)
			(stroke
				(width 0.1524)
				(type default)
			)
			(layer "F.SilkS")
		)
		(fp_line
			(start -0.12065 -0.305054)
			(end -0.12065 -0.2794)
			(stroke
				(width 0.1)
				(type default)
			)
			(layer "F.Fab")
		)
		(fp_line
			(start -0.67945 -0.305054)
			(end -0.12065 -0.305054)
			(stroke
				(width 0.1)
				(type default)
			)
			(layer "F.Fab")
		)
		(fp_line
			(start 0.67945 -0.3048)
			(end 0.67945 0.3048)
			(stroke
				(width 0.1)
				(type default)
			)
			(layer "F.Fab")
		)
		(fp_line
			(start 0.12065 -0.3048)
			(end 0.67945 -0.3048)
			(stroke
				(width 0.1)
				(type default)
			)
			(layer "F.Fab")
		)
		(fp_line
			(start 0.12065 -0.2794)
			(end 0.12065 -0.3048)
			(stroke
				(width 0.1)
				(type default)
			)
			(layer "F.Fab")
		)
		(fp_line
			(start -0.12065 -0.2794)
			(end 0.12065 -0.2794)
			(stroke
				(width 0.1)
				(type default)
			)
			(layer "F.Fab")
		)
		(fp_line
			(start 0.120396 0.2794)
			(end -0.12065 0.2794)
			(stroke
				(width 0.1)
				(type default)
			)
			(layer "F.Fab")
		)
		(fp_line
			(start -0.12065 0.2794)
			(end -0.12065 0.3048)
			(stroke
				(width 0.1)
				(type default)
			)
			(layer "F.Fab")
		)
		(fp_line
			(start 0.67945 0.3048)
			(end 0.120396 0.3048)
			(stroke
				(width 0.1)
				(type default)
			)
			(layer "F.Fab")
		)
		(fp_line
			(start 0.120396 0.3048)
			(end 0.120396 0.2794)
			(stroke
				(width 0.1)
				(type default)
			)
			(layer "F.Fab")
		)
		(fp_line
			(start -0.12065 0.3048)
			(end -0.67945 0.3048)
			(stroke
				(width 0.1)
				(type default)
			)
			(layer "F.Fab")
		)
		(fp_line
			(start -0.67945 0.3048)
			(end -0.67945 -0.305054)
			(stroke
				(width 0.1)
				(type default)
			)
			(layer "F.Fab")
		)
		(pad "1" smd circle
			(at -0.40005 0 90)
			(size 0 0)
			(layers "F.Cu" "F.Mask" "F.Paste")
			(net "P12V_SSD13_VIN_P")
		)
		(pad "2" smd circle
			(at 0.40005 0 90)
			(size 0 0)
			(layers "F.Cu" "F.Mask" "F.Paste")
			(net "P12V_SSD13_VIN_N")
		)
	)
	(footprint ""
		(layer "F.Cu")
		(at 336.042 -171.069 180)
		(property "Reference" "R4741"
			(at 0 0 180)
			(layer "F.SilkS")
			(hide yes)
			(effects
				(font
					(size 1.27 1.27)
				)
			)
		)
		(property "Value" ""
			(at 0 0 180)
			(layer "F.Fab")
			(effects
				(font
					(size 1.27 1.27)
				)
			)
		)
		(duplicate_pad_numbers_are_jumpers no)
		(fp_line
			(start 0.7874 0.4064)
			(end -0.7874 0.4064)
			(stroke
				(width 0.1524)
				(type default)
			)
			(layer "F.SilkS")
		)
		(fp_line
			(start 0.7874 -0.4064)
			(end 0.7874 0.4064)
			(stroke
				(width 0.1524)
				(type default)
			)
			(layer "F.SilkS")
		)
		(fp_line
			(start -0.7874 0.4064)
			(end -0.7874 -0.4064)
			(stroke
				(width 0.1524)
				(type default)
			)
			(layer "F.SilkS")
		)
		(fp_line
			(start -0.7874 -0.4064)
			(end 0.7874 -0.4064)
			(stroke
				(width 0.1524)
				(type default)
			)
			(layer "F.SilkS")
		)
		(fp_line
			(start 0.67945 0.3048)
			(end 0.120396 0.3048)
			(stroke
				(width 0.1)
				(type default)
			)
			(layer "F.Fab")
		)
		(fp_line
			(start 0.67945 -0.3048)
			(end 0.67945 0.3048)
			(stroke
				(width 0.1)
				(type default)
			)
			(layer "F.Fab")
		)
		(fp_line
			(start 0.12065 -0.2794)
			(end 0.12065 -0.3048)
			(stroke
				(width 0.1)
				(type default)
			)
			(layer "F.Fab")
		)
		(fp_line
			(start 0.12065 -0.3048)
			(end 0.67945 -0.3048)
			(stroke
				(width 0.1)
				(type default)
			)
			(layer "F.Fab")
		)
		(fp_line
			(start 0.120396 0.3048)
			(end 0.120396 0.2794)
			(stroke
				(width 0.1)
				(type default)
			)
			(layer "F.Fab")
		)
		(fp_line
			(start 0.120396 0.2794)
			(end -0.12065 0.2794)
			(stroke
				(width 0.1)
				(type default)
			)
			(layer "F.Fab")
		)
		(fp_line
			(start -0.12065 0.3048)
			(end -0.67945 0.3048)
			(stroke
				(width 0.1)
				(type default)
			)
			(layer "F.Fab")
		)
		(fp_line
			(start -0.12065 0.2794)
			(end -0.12065 0.3048)
			(stroke
				(width 0.1)
				(type default)
			)
			(layer "F.Fab")
		)
		(fp_line
			(start -0.12065 -0.2794)
			(end 0.12065 -0.2794)
			(stroke
				(width 0.1)
				(type default)
			)
			(layer "F.Fab")
		)
		(fp_line
			(start -0.12065 -0.305054)
			(end -0.12065 -0.2794)
			(stroke
				(width 0.1)
				(type default)
			)
			(layer "F.Fab")
		)
		(fp_line
			(start -0.67945 0.3048)
			(end -0.67945 -0.305054)
			(stroke
				(width 0.1)
				(type default)
			)
			(layer "F.Fab")
		)
		(fp_line
			(start -0.67945 -0.305054)
			(end -0.12065 -0.305054)
			(stroke
				(width 0.1)
				(type default)
			)
			(layer "F.Fab")
		)
		(pad "1" smd circle
			(at -0.40005 0 180)
			(size 0 0)
			(layers "F.Cu" "F.Mask" "F.Paste")
			(net "SSD10_PEX_PWR_EN_R")
		)
		(pad "2" smd circle
			(at 0.40005 0 180)
			(size 0 0)
			(layers "F.Cu" "F.Mask" "F.Paste")
			(net "GND")
		)
	)
	(footprint ""
		(layer "F.Cu")
		(at 430.41443 -140.134848 -90)
		(property "Reference" "R401"
			(at 0 0 270)
			(layer "F.SilkS")
			(hide yes)
			(effects
				(font
					(size 1.27 1.27)
				)
			)
		)
		(property "Value" ""
			(at 0 0 270)
			(layer "F.Fab")
			(effects
				(font
					(size 1.27 1.27)
				)
			)
		)
		(duplicate_pad_numbers_are_jumpers no)
		(fp_line
			(start -0.7874 0.4064)
			(end -0.7874 -0.4064)
			(stroke
				(width 0.1524)
				(type default)
			)
			(layer "F.SilkS")
		)
		(fp_line
			(start 0.7874 0.4064)
			(end -0.7874 0.4064)
			(stroke
				(width 0.1524)
				(type default)
			)
			(layer "F.SilkS")
		)
		(fp_line
			(start -0.7874 -0.4064)
			(end 0.7874 -0.4064)
			(stroke
				(width 0.1524)
				(type default)
			)
			(layer "F.SilkS")
		)
		(fp_line
			(start 0.7874 -0.4064)
			(end 0.7874 0.4064)
			(stroke
				(width 0.1524)
				(type default)
			)
			(layer "F.SilkS")
		)
		(fp_line
			(start -0.67945 0.3048)
			(end -0.67945 -0.305054)
			(stroke
				(width 0.1)
				(type default)
			)
			(layer "F.Fab")
		)
		(fp_line
			(start -0.12065 0.3048)
			(end -0.67945 0.3048)
			(stroke
				(width 0.1)
				(type default)
			)
			(layer "F.Fab")
		)
		(fp_line
			(start 0.120396 0.3048)
			(end 0.120396 0.2794)
			(stroke
				(width 0.1)
				(type default)
			)
			(layer "F.Fab")
		)
		(fp_line
			(start 0.67945 0.3048)
			(end 0.120396 0.3048)
			(stroke
				(width 0.1)
				(type default)
			)
			(layer "F.Fab")
		)
		(fp_line
			(start -0.12065 0.2794)
			(end -0.12065 0.3048)
			(stroke
				(width 0.1)
				(type default)
			)
			(layer "F.Fab")
		)
		(fp_line
			(start 0.120396 0.2794)
			(end -0.12065 0.2794)
			(stroke
				(width 0.1)
				(type default)
			)
			(layer "F.Fab")
		)
		(fp_line
			(start -0.12065 -0.2794)
			(end 0.12065 -0.2794)
			(stroke
				(width 0.1)
				(type default)
			)
			(layer "F.Fab")
		)
		(fp_line
			(start 0.12065 -0.2794)
			(end 0.12065 -0.3048)
			(stroke
				(width 0.1)
				(type default)
			)
			(layer "F.Fab")
		)
		(fp_line
			(start 0.12065 -0.3048)
			(end 0.67945 -0.3048)
			(stroke
				(width 0.1)
				(type default)
			)
			(layer "F.Fab")
		)
		(fp_line
			(start 0.67945 -0.3048)
			(end 0.67945 0.3048)
			(stroke
				(width 0.1)
				(type default)
			)
			(layer "F.Fab")
		)
		(fp_line
			(start -0.67945 -0.305054)
			(end -0.12065 -0.305054)
			(stroke
				(width 0.1)
				(type default)
			)
			(layer "F.Fab")
		)
		(fp_line
			(start -0.12065 -0.305054)
			(end -0.12065 -0.2794)
			(stroke
				(width 0.1)
				(type default)
			)
			(layer "F.Fab")
		)
		(pad "1" smd circle
			(at -0.40005 0 270)
			(size 0 0)
			(layers "F.Cu" "F.Mask" "F.Paste")
			(net "P3V3_AUX")
		)
		(pad "2" smd circle
			(at 0.40005 0 270)
			(size 0 0)
			(layers "F.Cu" "F.Mask" "F.Paste")
			(net "HP_NIC7_EN")
		)
	)
	(footprint ""
		(layer "F.Cu")
		(at 155.380436 -132.215382)
		(property "Reference" "C248"
			(at 0 0 0)
			(layer "F.SilkS")
			(hide yes)
			(effects
				(font
					(size 1.27 1.27)
				)
			)
		)
		(property "Value" ""
			(at 0 0 0)
			(layer "F.Fab")
			(effects
				(font
					(size 1.27 1.27)
				)
			)
		)
		(duplicate_pad_numbers_are_jumpers no)
		(fp_line
			(start -0.299974 -0.150114)
			(end 0.299974 -0.150114)
			(stroke
				(width 0.1)
				(type default)
			)
			(layer "F.Fab")
		)
		(fp_line
			(start -0.299974 0.150114)
			(end -0.299974 -0.150114)
			(stroke
				(width 0.1)
				(type default)
			)
			(layer "F.Fab")
		)
		(fp_line
			(start 0.299974 -0.150114)
			(end 0.299974 0.150114)
			(stroke
				(width 0.1)
				(type default)
			)
			(layer "F.Fab")
		)
		(fp_line
			(start 0.299974 0.150114)
			(end -0.299974 0.150114)
			(stroke
				(width 0.1)
				(type default)
			)
			(layer "F.Fab")
		)
		(pad "1" smd rect
			(at -0.2667 0)
			(size 0.3048 0.381)
			(layers "F.Cu" "F.Mask" "F.Paste")
			(net "P5E_PEX1_STN1_TX_DN<29>")
		)
		(pad "2" smd rect
			(at 0.2667 0)
			(size 0.3048 0.381)
			(layers "F.Cu" "F.Mask" "F.Paste")
			(net "P5E_PEX1_STN1_TX_C_DN<29>")
		)
	)
)
